# TIMECARD (Time Appliance Project (Time Card)) — schematic netlist excerpt (pin names and nets, part order shuffled) for the footprints in the layout excerpt that follows; sources: Cadence DE-HDL packaged netlist, KiCad conversion of R4006-B0001-02_R01.brd

C114  CAPACITOR  0.1UF 10V 10%  pkg SMC_0402R_H022  page 14 : \1\ = XP1R0V_FPGA_VCCINT ; \2\ = SG
R309  RESISTOR  4.7KOHM 1%  pkg SMC_0402R_H016  page 25 : \1\ = SG ; \2\ = FPGA_IO_5

(kicad_pcb
	(version 20260206)
	(generator "pcbnew")
	(generator_version "10.0")
	(general
		(thickness 1.6)
		(legacy_teardrops no)
	)
	(paper "A4")
	(title_block
		(title "timecard-production-celestica-r4006 — R4006-B0001-02_R01.brd")
		(comment 1 "Time Appliance Project (Time Card) / footprints 976-977 of 1113")
	)
	(layers
		(0 "F.Cu" signal "TOP")
		(4 "In1.Cu" signal "L02_GND1")
		(6 "In2.Cu" signal "L03_SIG1")
		(8 "In3.Cu" signal "L04_GND2")
		(10 "In4.Cu" signal "L05_VCC1")
		(12 "In5.Cu" signal "L06_VCC2")
		(14 "In6.Cu" signal "L07_GND3")
		(16 "In7.Cu" signal "L08_SIG2")
		(18 "In8.Cu" signal "L09_GND4")
		(2 "B.Cu" signal "BOTTOM")
		(9 "F.Adhes" user "F.Adhesive")
		(11 "B.Adhes" user "B.Adhesive")
		(13 "F.Paste" user "Package Geometry/Pastemask Top")
		(15 "B.Paste" user "Package Geometry/Pastemask Bottom")
		(5 "F.SilkS" user "Ref Des/Silkscreen Top")
		(7 "B.SilkS" user "Ref Des/Silkscreen Bottom")
		(1 "F.Mask" user "Board Geometry/Soldermask Top")
		(3 "B.Mask" user "Board Geometry/Soldermask Bottom")
		(17 "Dwgs.User" user "User.Drawings")
		(19 "Cmts.User" user "User.Comments")
		(21 "Eco1.User" user "User.Eco1")
		(23 "Eco2.User" user "User.Eco2")
		(25 "Edge.Cuts" user "Board Geometry/Outline")
		(27 "Margin" user)
		(31 "F.CrtYd" user "Package Geometry/Place Bound Top")
		(29 "B.CrtYd" user "Package Geometry/Place Bound Bottom")
		(35 "F.Fab" user "Ref Des/Assembly Top")
		(33 "B.Fab" user "Ref Des/Assembly Bottom")
	)
	(footprint ""
		(layer "B.Cu")
		(at 103.9622 -64.2874 90)
		(property "Reference" "R309"
			(at 3.5306 -0.11557 270)
			(unlocked yes)
			(layer "B.SilkS")
			(effects
				(font
					(size 0.7874 0.5842)
					(thickness 0.1524)
				)
				(justify mirror)
			)
		)
		(property "Value" "VAL*"
			(at -0.02032 2.13233 90)
			(unlocked yes)
			(layer "B.Fab")
			(hide yes)
			(effects
				(font
					(size 0.7874 0.5842)
					(thickness 0.1524)
				)
				(justify mirror)
			)
		)
		(property "Tolerance" "TOL*"
			(at -0.044704 3.05435 90)
			(unlocked yes)
			(layer "Cmts.User")
			(hide yes)
			(effects
				(font
					(size 0.7874 0.5842)
					(thickness 0.1524)
				)
				(justify mirror)
			)
		)
		(property "User Part Number" "PARTNUM*"
			(at -0.02032 4.024884 90)
			(unlocked yes)
			(layer "Cmts.User")
			(hide yes)
			(effects
				(font
					(size 0.7874 0.5842)
					(thickness 0.1524)
				)
				(justify mirror)
			)
		)
		(property "Device Type" "RESISTOR-G155-14701-01,4.7KOHMA"
			(at -0.008382 1.210564 90)
			(unlocked yes)
			(layer "B.Fab")
			(hide yes)
			(effects
				(font
					(size 0.7874 0.5842)
					(thickness 0.1524)
				)
				(justify mirror)
			)
		)
		(duplicate_pad_numbers_are_jumpers no)
		(fp_line
			(start 1.143 -0.5588)
			(end 1.143 0.5588)
			(stroke
				(width 0.1)
				(type default)
			)
			(layer "B.SilkS")
		)
		(fp_line
			(start -1.143 -0.5588)
			(end 1.143 -0.5588)
			(stroke
				(width 0.1)
				(type default)
			)
			(layer "B.SilkS")
		)
		(fp_line
			(start 1.143 0.5588)
			(end -1.143 0.5588)
			(stroke
				(width 0.1)
				(type default)
			)
			(layer "B.SilkS")
		)
		(fp_line
			(start -1.143 0.5588)
			(end -1.143 -0.5588)
			(stroke
				(width 0.1)
				(type default)
			)
			(layer "B.SilkS")
		)
		(fp_poly
			(pts
				(xy 1.143 0.5588) (xy -1.143 0.5588) (xy -1.143 -0.5588) (xy 1.143 -0.5588)
			)
			(stroke
				(width 0)
				(type default)
			)
			(fill no)
			(layer "B.CrtYd")
		)
		(fp_line
			(start 0.508 -0.3048)
			(end 0.508 0.3048)
			(stroke
				(width 0.1)
				(type default)
			)
			(layer "B.Fab")
		)
		(fp_line
			(start -0.508 -0.3048)
			(end 0.508 -0.3048)
			(stroke
				(width 0.1)
				(type default)
			)
			(layer "B.Fab")
		)
		(fp_line
			(start 0.508 0.3048)
			(end -0.508 0.3048)
			(stroke
				(width 0.1)
				(type default)
			)
			(layer "B.Fab")
		)
		(fp_line
			(start -0.508 0.3048)
			(end -0.508 -0.3048)
			(stroke
				(width 0.1)
				(type default)
			)
			(layer "B.Fab")
		)
		(pad "1" smd rect
			(at 0.5334 0 270)
			(size 0.7112 0.6096)
			(layers "B.Cu" "B.Mask" "B.Paste")
			(net "SG")
		)
		(pad "2" smd rect
			(at -0.5334 0 270)
			(size 0.7112 0.6096)
			(layers "B.Cu" "B.Mask" "B.Paste")
			(net "FPGA_IO_5")
		)
		(zone
			(layer "B.Cu")
			(hatch none 0.5)
			(connect_pads
				(clearance 0)
			)
			(min_thickness 0.25)
			(keepout
				(tracks not_allowed)
				(vias allowed)
				(pads allowed)
				(copperpour not_allowed)
				(footprints allowed)
			)
			(placement
				(enabled no)
				(sheetname "")
			)
			(fill
				(thermal_gap 0.5)
				(thermal_bridge_width 0.5)
				(island_removal_mode 0)
			)
			(polygon
				(pts
					(xy 104.267 -64.3636) (xy 103.6574 -64.3636) (xy 103.6574 -64.2112) (xy 104.267 -64.2112)
				)
			)
		)
		(zone
			(layer "B.Cu")
			(hatch none 0.5)
			(connect_pads
				(clearance 0)
			)
			(min_thickness 0.25)
			(keepout
				(tracks allowed)
				(vias not_allowed)
				(pads allowed)
				(copperpour not_allowed)
				(footprints allowed)
			)
			(placement
				(enabled no)
				(sheetname "")
			)
			(fill
				(thermal_gap 0.5)
				(thermal_bridge_width 0.5)
				(island_removal_mode 0)
			)
			(polygon
				(pts
					(xy 104.267 -64.3636) (xy 103.6574 -64.3636) (xy 103.6574 -64.2112) (xy 104.267 -64.2112)
				)
			)
		)
	)
	(footprint ""
		(layer "B.Cu")
		(at 109.347 -42.418 90)
		(property "Reference" "C114"
			(at -1.905 -41.56075 270)
			(unlocked yes)
			(layer "B.SilkS")
			(effects
				(font
					(size 0.635 0.4064)
					(thickness 0.1524)
				)
				(justify mirror)
			)
		)
		(property "Value" "VAL*"
			(at -0.0762 2.067306 90)
			(unlocked yes)
			(layer "B.Fab")
			(hide yes)
			(effects
				(font
					(size 0.7874 0.5842)
					(thickness 0.1524)
				)
				(justify mirror)
			)
		)
		(property "Device Type" "CAPACITOR-G105-0B104-CK,0.1UF,A"
			(at -0.0508 1.127506 90)
			(unlocked yes)
			(layer "B.Fab")
			(hide yes)
			(effects
				(font
					(size 0.7874 0.5842)
					(thickness 0.1524)
				)
				(justify mirror)
			)
		)
		(property "User Part Number" "PARTNUM*"
			(at -0.1016 4.023106 90)
			(unlocked yes)
			(layer "Cmts.User")
			(hide yes)
			(effects
				(font
					(size 0.7874 0.5842)
					(thickness 0.1524)
				)
				(justify mirror)
			)
		)
		(property "Tolerance" "TOL*"
			(at -0.0762 3.032506 90)
			(unlocked yes)
			(layer "Cmts.User")
			(hide yes)
			(effects
				(font
					(size 0.7874 0.5842)
					(thickness 0.1524)
				)
				(justify mirror)
			)
		)
		(duplicate_pad_numbers_are_jumpers no)
		(fp_line
			(start 1.143 -0.5588)
			(end 1.143 0.5588)
			(stroke
				(width 0.1)
				(type default)
			)
			(layer "B.SilkS")
		)
		(fp_line
			(start -1.143 -0.5588)
			(end 1.143 -0.5588)
			(stroke
				(width 0.1)
				(type default)
			)
			(layer "B.SilkS")
		)
		(fp_line
			(start 1.143 0.5588)
			(end -1.143 0.5588)
			(stroke
				(width 0.1)
				(type default)
			)
			(layer "B.SilkS")
		)
		(fp_line
			(start -1.143 0.5588)
			(end -1.143 -0.5588)
			(stroke
				(width 0.1)
				(type default)
			)
			(layer "B.SilkS")
		)
		(fp_rect
			(start -1.143 -0.5588)
			(end 1.143 0.5588)
			(stroke
				(width 0)
				(type default)
			)
			(fill no)
			(layer "B.CrtYd")
		)
		(fp_line
			(start 0.508 -0.3048)
			(end 0.508 0.3048)
			(stroke
				(width 0.1)
				(type default)
			)
			(layer "B.Fab")
		)
		(fp_line
			(start -0.508 -0.3048)
			(end 0.508 -0.3048)
			(stroke
				(width 0.1)
				(type default)
			)
			(layer "B.Fab")
		)
		(fp_line
			(start 0.508 0.3048)
			(end -0.508 0.3048)
			(stroke
				(width 0.1)
				(type default)
			)
			(layer "B.Fab")
		)
		(fp_line
			(start -0.508 0.3048)
			(end -0.508 -0.3048)
			(stroke
				(width 0.1)
				(type default)
			)
			(layer "B.Fab")
		)
		(pad "1" smd rect
			(at 0.5334 0 270)
			(size 0.7112 0.6096)
			(layers "B.Cu" "B.Mask" "B.Paste")
			(net "XP1R0V_FPGA_VCCINT")
		)
		(pad "2" smd rect
			(at -0.5334 0 270)
			(size 0.7112 0.6096)
			(layers "B.Cu" "B.Mask" "B.Paste")
			(net "SG")
		)
		(zone
			(layer "B.Cu")
			(hatch none 0.5)
			(connect_pads
				(clearance 0)
			)
			(min_thickness 0.25)
			(keepout
				(tracks allowed)
				(vias not_allowed)
				(pads allowed)
				(copperpour not_allowed)
				(footprints allowed)
			)
			(placement
				(enabled no)
				(sheetname "")
			)
			(fill
				(thermal_gap 0.5)
				(thermal_bridge_width 0.5)
				(island_removal_mode 0)
			)
			(polygon
				(pts
					(xy 109.0422 -42.3418) (xy 109.6518 -42.3418) (xy 109.6518 -42.4942) (xy 109.0422 -42.4942)
				)
			)
		)
	)
)
